# BASEBOARD_FAB2 (Tioga Pass) — schematic netlist excerpt (pin names and nets, part order shuffled) for the footprints in the layout excerpt that follows; sources: Cadence DE-HDL packaged netlist, KiCad conversion of Wiwynn_Tioga_Pass_MB.brd

R25W81  RES  33.2 1% CHIP  pkg 0402  page 146 : A = SPI_BMC_BT_CLK ; B = SPI_BMC_BT_CLK_R
C9E4  CAP_A  0.1UF 16V 10% X7R  pkg 0402V  page 139 : A = PE_PCH_SPRV_RX_DP ; B = PE_PCH_SPRV_RX_C_DP
C3D6  CAP_A  22.0UF 4V 20% X6S  pkg 0603V  page 76 : A = PVCCMCP_CPU1 ; B = GND

(kicad_pcb
	(version 20260206)
	(generator "pcbnew")
	(generator_version "10.0")
	(general
		(thickness 1.6)
		(legacy_teardrops no)
	)
	(paper "A4")
	(title_block
		(title "Wiwynn_Tioga_Pass_MB.brd")
		(comment 1 "Tioga Pass / footprints 1404-1406 of 4770")
	)
	(layers
		(0 "F.Cu" signal "TOP")
		(4 "In1.Cu" signal "L2GND")
		(6 "In2.Cu" signal "L3")
		(8 "In3.Cu" signal "L4GND")
		(10 "In4.Cu" signal "L5")
		(12 "In5.Cu" signal "L6GND")
		(14 "In6.Cu" signal "L7VCC")
		(16 "In7.Cu" signal "L8VCC")
		(18 "In8.Cu" signal "L9GND")
		(20 "In9.Cu" signal "L10")
		(22 "In10.Cu" signal "L11GND")
		(24 "In11.Cu" signal "L12")
		(26 "In12.Cu" signal "L13GND")
		(2 "B.Cu" signal "BOTTOM")
		(9 "F.Adhes" user "F.Adhesive")
		(11 "B.Adhes" user "B.Adhesive")
		(13 "F.Paste" user "Package Geometry/Pastemask Top")
		(15 "B.Paste" user "Package Geometry/Pastemask Bottom")
		(5 "F.SilkS" user "Ref Des/Silkscreen Top")
		(7 "B.SilkS" user "Ref Des/Silkscreen Bottom")
		(1 "F.Mask" user "Board Geometry/Soldermask Top")
		(3 "B.Mask" user "Board Geometry/Soldermask Bottom")
		(17 "Dwgs.User" user "User.Drawings")
		(19 "Cmts.User" user "User.Comments")
		(21 "Eco1.User" user "User.Eco1")
		(23 "Eco2.User" user "User.Eco2")
		(25 "Edge.Cuts" user "Board Geometry/Outline")
		(27 "Margin" user)
		(31 "F.CrtYd" user "Package Geometry/Place Bound Top")
		(29 "B.CrtYd" user "Package Geometry/Place Bound Bottom")
		(35 "F.Fab" user "Ref Des/Assembly Top")
		(33 "B.Fab" user "Ref Des/Assembly Bottom")
	)
	(footprint ""
		(layer "F.Cu")
		(at 110.792768 -79.6036 180)
		(property "Reference" "C3D6"
			(at 0 0 180)
			(layer "F.SilkS")
			(hide yes)
			(effects
				(font
					(size 1.27 1.27)
				)
			)
		)
		(property "Value" ""
			(at 0 0 180)
			(layer "F.Fab")
			(effects
				(font
					(size 1.27 1.27)
				)
			)
		)
		(duplicate_pad_numbers_are_jumpers no)
		(fp_poly
			(pts
				(xy -0.4953 -0.2032) (xy 0.4953 -0.2032) (xy 0.4953 1.6002) (xy -0.4953 1.6002)
			)
			(stroke
				(width 0)
				(type default)
			)
			(fill no)
			(layer "F.CrtYd")
		)
		(fp_line
			(start 0.4953 1.6002)
			(end -0.4953 1.6002)
			(stroke
				(width 0.1)
				(type default)
			)
			(layer "F.Fab")
		)
		(fp_line
			(start 0.4953 -0.2032)
			(end 0.4953 1.6002)
			(stroke
				(width 0.1)
				(type default)
			)
			(layer "F.Fab")
		)
		(fp_line
			(start -0.4953 1.6002)
			(end -0.4953 -0.2032)
			(stroke
				(width 0.1)
				(type default)
			)
			(layer "F.Fab")
		)
		(fp_line
			(start -0.4953 -0.2032)
			(end 0.4953 -0.2032)
			(stroke
				(width 0.1)
				(type default)
			)
			(layer "F.Fab")
		)
		(pad "1" smd rect
			(at 0 0 180)
			(size 0.762 0.889)
			(layers "F.Cu" "F.Mask" "F.Paste")
			(net "PVCCMCP_CPU1")
		)
		(pad "2" smd rect
			(at 0 1.397 180)
			(size 0.762 0.889)
			(layers "F.Cu" "F.Mask" "F.Paste")
			(net "GND")
		)
		(zone
			(layer "F.Cu")
			(hatch none 0.5)
			(connect_pads
				(clearance 0)
			)
			(min_thickness 0.25)
			(keepout
				(tracks not_allowed)
				(vias allowed)
				(pads allowed)
				(copperpour not_allowed)
				(footprints allowed)
			)
			(placement
				(enabled no)
				(sheetname "")
			)
			(fill
				(thermal_gap 0.5)
				(thermal_bridge_width 0.5)
				(island_removal_mode 0)
			)
			(polygon
				(pts
					(xy 111.173768 -80.0481) (xy 110.411768 -80.0481) (xy 110.411768 -80.5561) (xy 111.173768 -80.5561)
				)
			)
		)
	)
	(footprint ""
		(layer "F.Cu")
		(at 485.4956 -50.2539 180)
		(property "Reference" "C9E4"
			(at 0 0 180)
			(layer "F.SilkS")
			(hide yes)
			(effects
				(font
					(size 1.27 1.27)
				)
			)
		)
		(property "Value" ""
			(at 0 0 180)
			(layer "F.Fab")
			(effects
				(font
					(size 1.27 1.27)
				)
			)
		)
		(duplicate_pad_numbers_are_jumpers no)
		(fp_poly
			(pts
				(xy 0.3048 -0.1016) (xy 0.3048 0.9906) (xy -0.3048 0.9906) (xy -0.3048 -0.1016)
			)
			(stroke
				(width 0)
				(type default)
			)
			(fill no)
			(layer "F.CrtYd")
		)
		(fp_line
			(start 0.3048 0.9906)
			(end 0.3048 -0.1016)
			(stroke
				(width 0.1)
				(type default)
			)
			(layer "F.Fab")
		)
		(fp_line
			(start 0.3048 -0.1016)
			(end -0.3048 -0.1016)
			(stroke
				(width 0.1)
				(type default)
			)
			(layer "F.Fab")
		)
		(fp_line
			(start -0.3048 0.9906)
			(end 0.3048 0.9906)
			(stroke
				(width 0.1)
				(type default)
			)
			(layer "F.Fab")
		)
		(fp_line
			(start -0.3048 -0.1016)
			(end -0.3048 0.9906)
			(stroke
				(width 0.1)
				(type default)
			)
			(layer "F.Fab")
		)
		(pad "1" smd rect
			(at 0 0 180)
			(size 0.508 0.508)
			(layers "F.Cu" "F.Mask" "F.Paste")
			(net "PE_PCH_SPRV_RX_DP")
		)
		(pad "2" smd rect
			(at 0 0.889 180)
			(size 0.508 0.508)
			(layers "F.Cu" "F.Mask" "F.Paste")
			(net "PE_PCH_SPRV_RX_C_DP")
		)
		(zone
			(layer "F.Cu")
			(hatch none 0.5)
			(connect_pads
				(clearance 0)
			)
			(min_thickness 0.25)
			(keepout
				(tracks not_allowed)
				(vias allowed)
				(pads allowed)
				(copperpour not_allowed)
				(footprints allowed)
			)
			(placement
				(enabled no)
				(sheetname "")
			)
			(fill
				(thermal_gap 0.5)
				(thermal_bridge_width 0.5)
				(island_removal_mode 0)
			)
			(polygon
				(pts
					(xy 485.7496 -50.8889) (xy 485.2416 -50.8889) (xy 485.2416 -50.5079) (xy 485.7496 -50.5079)
				)
			)
		)
		(zone
			(layer "F.Cu")
			(hatch none 0.5)
			(connect_pads
				(clearance 0)
			)
			(min_thickness 0.25)
			(keepout
				(tracks allowed)
				(vias not_allowed)
				(pads allowed)
				(copperpour not_allowed)
				(footprints allowed)
			)
			(placement
				(enabled no)
				(sheetname "")
			)
			(fill
				(thermal_gap 0.5)
				(thermal_bridge_width 0.5)
				(island_removal_mode 0)
			)
			(polygon
				(pts
					(xy 485.7496 -50.5079) (xy 485.2416 -50.5079) (xy 485.2416 -50.8889) (xy 485.7496 -50.8889)
				)
			)
		)
	)
	(footprint ""
		(layer "F.Cu")
		(at 431.7746 -44.2849 -90)
		(property "Reference" "R25W81"
			(at -0.8382 -0.67818 270)
			(unlocked yes)
			(layer "F.SilkS")
			(effects
				(font
					(size 0.4064 0.254)
					(thickness 0.1524)
				)
				(justify left)
			)
		)
		(property "Value" ""
			(at 0 0 270)
			(layer "F.Fab")
			(effects
				(font
					(size 1.27 1.27)
				)
			)
		)
		(duplicate_pad_numbers_are_jumpers no)
		(fp_poly
			(pts
				(xy -0.2794 -0.1016) (xy 0.2794 -0.1016) (xy 0.2794 0.9906) (xy -0.2794 0.9906)
			)
			(stroke
				(width 0)
				(type default)
			)
			(fill no)
			(layer "F.CrtYd")
		)
		(fp_line
			(start -0.2794 0.9906)
			(end 0.2794 0.9906)
			(stroke
				(width 0.1)
				(type default)
			)
			(layer "F.Fab")
		)
		(fp_line
			(start 0.2794 0.9906)
			(end 0.2794 -0.1016)
			(stroke
				(width 0.1)
				(type default)
			)
			(layer "F.Fab")
		)
		(fp_line
			(start -0.2794 -0.1016)
			(end -0.2794 0.9906)
			(stroke
				(width 0.1)
				(type default)
			)
			(layer "F.Fab")
		)
		(fp_line
			(start 0.2794 -0.1016)
			(end -0.2794 -0.1016)
			(stroke
				(width 0.1)
				(type default)
			)
			(layer "F.Fab")
		)
		(pad "1" smd rect
			(at 0 0 270)
			(size 0.508 0.508)
			(layers "F.Cu" "F.Mask" "F.Paste")
			(net "SPI_BMC_BT_CLK")
		)
		(pad "2" smd rect
			(at 0 0.889 270)
			(size 0.508 0.508)
			(layers "F.Cu" "F.Mask" "F.Paste")
			(net "SPI_BMC_BT_CLK_R")
		)
		(zone
			(layer "F.Cu")
			(hatch none 0.5)
			(connect_pads
				(clearance 0)
			)
			(min_thickness 0.25)
			(keepout
				(tracks not_allowed)
				(vias allowed)
				(pads allowed)
				(copperpour not_allowed)
				(footprints allowed)
			)
			(placement
				(enabled no)
				(sheetname "")
			)
			(fill
				(thermal_gap 0.5)
				(thermal_bridge_width 0.5)
				(island_removal_mode 0)
			)
			(polygon
				(pts
					(xy 431.1396 -44.5389) (xy 431.1396 -44.0309) (xy 431.5206 -44.0309) (xy 431.5206 -44.5389)
				)
			)
		)
		(zone
			(layer "F.Cu")
			(hatch none 0.5)
			(connect_pads
				(clearance 0)
			)
			(min_thickness 0.25)
			(keepout
				(tracks allowed)
				(vias not_allowed)
				(pads allowed)
				(copperpour not_allowed)
				(footprints allowed)
			)
			(placement
				(enabled no)
				(sheetname "")
			)
			(fill
				(thermal_gap 0.5)
				(thermal_bridge_width 0.5)
				(island_removal_mode 0)
			)
			(polygon
				(pts
					(xy 431.5206 -44.5389) (xy 431.5206 -44.0309) (xy 431.1396 -44.0309) (xy 431.1396 -44.5389)
				)
			)
		)
	)
)
